# S9S_MB_2U (Grand Teton) — schematic netlist excerpt (pin names and nets, part order shuffled) for the footprints in the layout excerpt that follows; sources: Cadence DE-HDL packaged netlist, KiCad conversion of 03242023_DA0F0TMBIJ0_F0T_Motherboard_J_brd_V01_OCP.brd

PC2181  Q_CAP  1UF 25V 10% X6S  pkg C0402  page 302 : A = HSC_VDD_R_2 ; B = AGND_HSC
PL118  Q_INDUCTOR  0.68UH IND  pkg SMLF  page 281 : \1\ = SW_PVPP_HBM_CPU0_SW ; \2\ = PVPP_HBM_CPU0
R4508  Q_RES  33.2 1% CHIP  pkg 0402LF  page 240 : A = SMB_1_PLD_3V3AUX_SCL ; B = SMB_1_PLD_3V3AUX_SCL_R3

(kicad_pcb
	(version 20260206)
	(generator "pcbnew")
	(generator_version "10.0")
	(general
		(thickness 1.6)
		(legacy_teardrops no)
	)
	(paper "A4")
	(title_block
		(title "03242023_DA0F0TMBIJ0_F0T_Motherboard_J_brd_V01_OCP.brd")
		(comment 1 "Grand Teton / footprints 3008-3010 of 6105")
	)
	(layers
		(0 "F.Cu" signal "TOP")
		(4 "In1.Cu" signal "GND")
		(6 "In2.Cu" signal "IN1")
		(8 "In3.Cu" signal "GND1")
		(10 "In4.Cu" signal "IN2")
		(12 "In5.Cu" signal "GND2")
		(14 "In6.Cu" signal "IN3")
		(16 "In7.Cu" signal "GND3")
		(18 "In8.Cu" signal "VCC")
		(20 "In9.Cu" signal "VCC1")
		(22 "In10.Cu" signal "GND4")
		(24 "In11.Cu" signal "IN4")
		(26 "In12.Cu" signal "GND5")
		(28 "In13.Cu" signal "IN5")
		(30 "In14.Cu" signal "GND6")
		(32 "In15.Cu" signal "IN6")
		(34 "In16.Cu" signal "GND7")
		(2 "B.Cu" signal "BOTTOM")
		(9 "F.Adhes" user "F.Adhesive")
		(11 "B.Adhes" user "B.Adhesive")
		(13 "F.Paste" user "Package Geometry/Pastemask Top")
		(15 "B.Paste" user "Package Geometry/Pastemask Bottom")
		(5 "F.SilkS" user "Ref Des/Silkscreen Top")
		(7 "B.SilkS" user "Ref Des/Silkscreen Bottom")
		(1 "F.Mask" user "Board Geometry/Soldermask Top")
		(3 "B.Mask" user "Board Geometry/Soldermask Bottom")
		(17 "Dwgs.User" user "User.Drawings")
		(19 "Cmts.User" user "User.Comments")
		(21 "Eco1.User" user "User.Eco1")
		(23 "Eco2.User" user "User.Eco2")
		(25 "Edge.Cuts" user "Board Geometry/Outline")
		(27 "Margin" user)
		(31 "F.CrtYd" user "Package Geometry/Place Bound Top")
		(29 "B.CrtYd" user "Package Geometry/Place Bound Bottom")
		(35 "F.Fab" user "Ref Des/Assembly Top")
		(33 "B.Fab" user "Ref Des/Assembly Bottom")
	)
	(footprint ""
		(layer "F.Cu")
		(at 207.074008 -402.994622 90)
		(property "Reference" "PC2181"
			(at 0 0 90)
			(layer "F.SilkS")
			(hide yes)
			(effects
				(font
					(size 1.27 1.27)
				)
			)
		)
		(property "Value" ""
			(at 0 0 90)
			(layer "F.Fab")
			(effects
				(font
					(size 1.27 1.27)
				)
			)
		)
		(duplicate_pad_numbers_are_jumpers no)
		(fp_line
			(start 0.7874 -0.4064)
			(end 0.7874 0.4064)
			(stroke
				(width 0.1524)
				(type default)
			)
			(layer "F.SilkS")
		)
		(fp_line
			(start -0.7874 -0.4064)
			(end 0.7874 -0.4064)
			(stroke
				(width 0.1524)
				(type default)
			)
			(layer "F.SilkS")
		)
		(fp_line
			(start 0.7874 0.4064)
			(end -0.7874 0.4064)
			(stroke
				(width 0.1524)
				(type default)
			)
			(layer "F.SilkS")
		)
		(fp_line
			(start -0.7874 0.4064)
			(end -0.7874 -0.4064)
			(stroke
				(width 0.1524)
				(type default)
			)
			(layer "F.SilkS")
		)
		(fp_line
			(start -0.12065 -0.305054)
			(end -0.12065 -0.2794)
			(stroke
				(width 0.1)
				(type default)
			)
			(layer "F.Fab")
		)
		(fp_line
			(start -0.67945 -0.305054)
			(end -0.12065 -0.305054)
			(stroke
				(width 0.1)
				(type default)
			)
			(layer "F.Fab")
		)
		(fp_line
			(start 0.67945 -0.3048)
			(end 0.67945 0.3048)
			(stroke
				(width 0.1)
				(type default)
			)
			(layer "F.Fab")
		)
		(fp_line
			(start 0.12065 -0.3048)
			(end 0.67945 -0.3048)
			(stroke
				(width 0.1)
				(type default)
			)
			(layer "F.Fab")
		)
		(fp_line
			(start 0.12065 -0.2794)
			(end 0.12065 -0.3048)
			(stroke
				(width 0.1)
				(type default)
			)
			(layer "F.Fab")
		)
		(fp_line
			(start -0.12065 -0.2794)
			(end 0.12065 -0.2794)
			(stroke
				(width 0.1)
				(type default)
			)
			(layer "F.Fab")
		)
		(fp_line
			(start 0.120396 0.2794)
			(end -0.12065 0.2794)
			(stroke
				(width 0.1)
				(type default)
			)
			(layer "F.Fab")
		)
		(fp_line
			(start -0.12065 0.2794)
			(end -0.12065 0.3048)
			(stroke
				(width 0.1)
				(type default)
			)
			(layer "F.Fab")
		)
		(fp_line
			(start 0.67945 0.3048)
			(end 0.120396 0.3048)
			(stroke
				(width 0.1)
				(type default)
			)
			(layer "F.Fab")
		)
		(fp_line
			(start 0.120396 0.3048)
			(end 0.120396 0.2794)
			(stroke
				(width 0.1)
				(type default)
			)
			(layer "F.Fab")
		)
		(fp_line
			(start -0.12065 0.3048)
			(end -0.67945 0.3048)
			(stroke
				(width 0.1)
				(type default)
			)
			(layer "F.Fab")
		)
		(fp_line
			(start -0.67945 0.3048)
			(end -0.67945 -0.305054)
			(stroke
				(width 0.1)
				(type default)
			)
			(layer "F.Fab")
		)
		(pad "1" smd circle
			(at -0.40005 0 90)
			(size 0 0)
			(layers "F.Cu" "F.Mask" "F.Paste")
			(net "HSC_VDD_R_2")
		)
		(pad "2" smd circle
			(at 0.40005 0 90)
			(size 0 0)
			(layers "F.Cu" "F.Mask" "F.Paste")
			(net "AGND_HSC")
		)
	)
	(footprint ""
		(layer "F.Cu")
		(at 373.736616 -366.581944 90)
		(property "Reference" "PL118"
			(at 4.647438 -1.728724 0)
			(unlocked yes)
			(layer "F.SilkS")
			(effects
				(font
					(size 0.7874 0.5842)
					(thickness 0.1524)
				)
				(justify left)
			)
		)
		(property "Value" ""
			(at 0 0 90)
			(layer "F.Fab")
			(effects
				(font
					(size 1.27 1.27)
				)
			)
		)
		(duplicate_pad_numbers_are_jumpers no)
		(fp_line
			(start 3.64998 -3.350006)
			(end 3.64998 -1.8034)
			(stroke
				(width 0.1524)
				(type default)
			)
			(layer "F.SilkS")
		)
		(fp_line
			(start -3.6576 -3.350006)
			(end 3.64998 -3.350006)
			(stroke
				(width 0.1524)
				(type default)
			)
			(layer "F.SilkS")
		)
		(fp_line
			(start -3.64998 -1.8034)
			(end -3.64998 -3.350006)
			(stroke
				(width 0.1524)
				(type default)
			)
			(layer "F.SilkS")
		)
		(fp_line
			(start 3.64998 1.8034)
			(end 3.64998 3.350006)
			(stroke
				(width 0.1524)
				(type default)
			)
			(layer "F.SilkS")
		)
		(fp_line
			(start 3.64998 3.350006)
			(end -3.64998 3.350006)
			(stroke
				(width 0.1524)
				(type default)
			)
			(layer "F.SilkS")
		)
		(fp_line
			(start -3.64998 3.350006)
			(end -3.64998 1.8288)
			(stroke
				(width 0.1524)
				(type default)
			)
			(layer "F.SilkS")
		)
		(fp_line
			(start 3.64998 -3.350006)
			(end 3.64998 3.350006)
			(stroke
				(width 0.1)
				(type default)
			)
			(layer "F.Fab")
		)
		(fp_line
			(start -3.64998 -3.350006)
			(end 3.64998 -3.350006)
			(stroke
				(width 0.1)
				(type default)
			)
			(layer "F.Fab")
		)
		(fp_line
			(start 3.64998 3.350006)
			(end -3.64998 3.350006)
			(stroke
				(width 0.1)
				(type default)
			)
			(layer "F.Fab")
		)
		(fp_line
			(start -3.64998 3.350006)
			(end -3.64998 -3.350006)
			(stroke
				(width 0.1)
				(type default)
			)
			(layer "F.Fab")
		)
		(pad "1" smd rect
			(at -2.92481 0 90)
			(size 2.15392 3.302)
			(layers "F.Cu" "F.Mask" "F.Paste")
			(net "SW_PVPP_HBM_CPU0_SW")
		)
		(pad "2" smd rect
			(at 2.92481 0 90)
			(size 2.15392 3.302)
			(layers "F.Cu" "F.Mask" "F.Paste")
			(net "PVPP_HBM_CPU0")
		)
	)
	(footprint ""
		(layer "F.Cu")
		(at 162.179 -20.665948 -90)
		(property "Reference" "R4508"
			(at 0 0 270)
			(layer "F.SilkS")
			(hide yes)
			(effects
				(font
					(size 1.27 1.27)
				)
			)
		)
		(property "Value" ""
			(at 0 0 270)
			(layer "F.Fab")
			(effects
				(font
					(size 1.27 1.27)
				)
			)
		)
		(duplicate_pad_numbers_are_jumpers no)
		(fp_line
			(start -0.7874 0.4064)
			(end -0.7874 -0.4064)
			(stroke
				(width 0.1524)
				(type default)
			)
			(layer "F.SilkS")
		)
		(fp_line
			(start 0.7874 0.4064)
			(end -0.7874 0.4064)
			(stroke
				(width 0.1524)
				(type default)
			)
			(layer "F.SilkS")
		)
		(fp_line
			(start -0.7874 -0.4064)
			(end 0.7874 -0.4064)
			(stroke
				(width 0.1524)
				(type default)
			)
			(layer "F.SilkS")
		)
		(fp_line
			(start 0.7874 -0.4064)
			(end 0.7874 0.4064)
			(stroke
				(width 0.1524)
				(type default)
			)
			(layer "F.SilkS")
		)
		(fp_line
			(start -0.67945 0.3048)
			(end -0.67945 -0.305054)
			(stroke
				(width 0.1)
				(type default)
			)
			(layer "F.Fab")
		)
		(fp_line
			(start -0.12065 0.3048)
			(end -0.67945 0.3048)
			(stroke
				(width 0.1)
				(type default)
			)
			(layer "F.Fab")
		)
		(fp_line
			(start 0.120396 0.3048)
			(end 0.120396 0.2794)
			(stroke
				(width 0.1)
				(type default)
			)
			(layer "F.Fab")
		)
		(fp_line
			(start 0.67945 0.3048)
			(end 0.120396 0.3048)
			(stroke
				(width 0.1)
				(type default)
			)
			(layer "F.Fab")
		)
		(fp_line
			(start -0.12065 0.2794)
			(end -0.12065 0.3048)
			(stroke
				(width 0.1)
				(type default)
			)
			(layer "F.Fab")
		)
		(fp_line
			(start 0.120396 0.2794)
			(end -0.12065 0.2794)
			(stroke
				(width 0.1)
				(type default)
			)
			(layer "F.Fab")
		)
		(fp_line
			(start -0.12065 -0.2794)
			(end 0.12065 -0.2794)
			(stroke
				(width 0.1)
				(type default)
			)
			(layer "F.Fab")
		)
		(fp_line
			(start 0.12065 -0.2794)
			(end 0.12065 -0.3048)
			(stroke
				(width 0.1)
				(type default)
			)
			(layer "F.Fab")
		)
		(fp_line
			(start 0.12065 -0.3048)
			(end 0.67945 -0.3048)
			(stroke
				(width 0.1)
				(type default)
			)
			(layer "F.Fab")
		)
		(fp_line
			(start 0.67945 -0.3048)
			(end 0.67945 0.3048)
			(stroke
				(width 0.1)
				(type default)
			)
			(layer "F.Fab")
		)
		(fp_line
			(start -0.67945 -0.305054)
			(end -0.12065 -0.305054)
			(stroke
				(width 0.1)
				(type default)
			)
			(layer "F.Fab")
		)
		(fp_line
			(start -0.12065 -0.305054)
			(end -0.12065 -0.2794)
			(stroke
				(width 0.1)
				(type default)
			)
			(layer "F.Fab")
		)
		(pad "1" smd circle
			(at -0.40005 0 270)
			(size 0 0)
			(layers "F.Cu" "F.Mask" "F.Paste")
			(net "SMB_1_PLD_3V3AUX_SCL")
		)
		(pad "2" smd circle
			(at 0.40005 0 270)
			(size 0 0)
			(layers "F.Cu" "F.Mask" "F.Paste")
			(net "SMB_1_PLD_3V3AUX_SCL_R3")
		)
	)
)
